FILE_TYPE = CONNECTIVITY;
{Allegro Design Entry HDL 16.6-p007 (v16-6-112F) 10/10/2012}
"PAGE_NUMBER" = 78;
0"NC";
1"M_G_DQS_DN<17:0>";
2"M_G_DQS_DP<17:0>";
3"M_G_DQ<63:0>";
4"M_G_MA<17:0>";
5"M_G_BA<1:0>";
6"M_G_BG<1:0>";
7"M_G_CLK_DN<3:0>";
8"M_G_CS_N<7:0>";
9"M_G_CLK_DP<3:0>";
10"M_G_CKE<3:0>";
11"M_G_ODT<3:0>";
12"M_G_ECC<7:0>";
13"GND\g";
14"PVPP_GHJ\g";
15"GND\g";
16"GND\g";
17"P12V_NVDIMM_GHJ\g";
18"GND\g";
19"PVPP_GHJ\g";
20"PVDDQ_GHJ\g";
21"PVTT_GHJ\g";
22"M_G_MA<7>";
23"M_G_DQS_DN<1>";
24"M_G_DQ<59>";
25"M_G_DQS_DP<5>";
26"M_G_DQS_DN<5>";
27"M_G_DQ<57>";
28"M_G_VREF";
29"M_G_ACT_N";
30"M_G_ALERT_N";
31"TP_CH_G_DIMM0_RFU_2";
32"TP_CH_G_DIMM0_RFU_0";
33"TP_CH_G_DIMM0_RFU_1";
34"FM_ADR_COMPLETE_GHJ_N";
35"FM_DIMM_EVENT_COD_N";
36"SMB_DDR_GHJ_VPP_SDA";
37"SMB_DDR_GHJ_VPP_SCL";
38"M_G_ECC<4>";
39"M_G_ECC<3>";
40"M_G_ECC<2>";
41"M_G_ECC<1>";
42"M_G_ECC<0>";
43"M_G_PAR";
44"M_GHJ_RST_N";
45"M_G_ECC<6>";
46"M_G_ECC<5>";
47"M_G_ECC<7>";
48"M_G_ODT<2>";
49"M_G_ODT<3>";
50"M_G_CKE<3>";
51"M_G_CKE<2>";
52"M_G_CLK_DN<3>";
53"M_G_CLK_DP<2>";
54"M_G_CS_N<7>";
55"M_G_CLK_DP<3>";
56"M_G_CS_N<6>";
57"M_G_CS_N<5>";
58"M_G_CS_N<4>";
59"M_G_CLK_DN<2>";
60"M_G_C<2>";
61"M_G_BA<1>";
62"M_G_MA<0>";
63"M_G_MA<1>";
64"M_G_MA<3>";
65"M_G_MA<4>";
66"M_G_BG<0>";
67"M_G_BG<1>";
68"M_G_BA<0>";
69"M_G_MA<2>";
70"M_G_MA<12>";
71"M_G_MA<13>";
72"M_G_MA<5>";
73"M_G_MA<6>";
74"M_G_MA<8>";
75"M_G_MA<9>";
76"M_G_MA<10>";
77"M_G_MA<11>";
78"M_G_MA<14>";
79"M_G_MA<17>";
80"M_G_MA<15>";
81"M_G_MA<16>";
82"M_G_DQ<63>";
83"M_G_DQ<29>";
84"M_G_DQ<28>";
85"M_G_DQ<62>";
86"M_G_DQ<61>";
87"M_G_DQ<60>";
88"M_G_DQ<56>";
89"M_G_DQ<55>";
90"M_G_DQ<46>";
91"M_G_DQ<45>";
92"M_G_DQ<44>";
93"M_G_DQ<43>";
94"M_G_DQ<42>";
95"M_G_DQ<41>";
96"M_G_DQ<40>";
97"M_G_DQ<39>";
98"M_G_DQ<37>";
99"M_G_DQ<34>";
100"M_G_DQ<33>";
101"M_G_DQ<32>";
102"M_G_DQ<31>";
103"M_G_DQ<30>";
104"M_G_DQ<25>";
105"M_G_DQ<24>";
106"M_G_DQ<23>";
107"M_G_DQ<22>";
108"M_G_DQ<21>";
109"M_G_DQ<20>";
110"M_G_DQ<19>";
111"M_G_DQ<18>";
112"M_G_DQ<16>";
113"M_G_DQ<14>";
114"M_G_DQ<13>";
115"M_G_DQ<12>";
116"M_G_DQ<11>";
117"M_G_DQ<9>";
118"M_G_DQ<7>";
119"M_G_DQ<6>";
120"M_G_DQ<1>";
121"M_G_DQ<0>";
122"M_G_DQ<35>";
123"M_G_DQ<36>";
124"M_G_DQ<38>";
125"M_G_DQ<26>";
126"M_G_DQ<15>";
127"M_G_DQ<17>";
128"M_G_DQ<58>";
129"M_G_DQ<54>";
130"M_G_DQ<53>";
131"M_G_DQ<52>";
132"M_G_DQ<51>";
133"M_G_DQ<50>";
134"M_G_DQ<49>";
135"M_G_DQ<48>";
136"M_G_DQ<47>";
137"M_G_DQ<2>";
138"M_G_DQ<3>";
139"M_G_DQ<4>";
140"M_G_DQ<5>";
141"M_G_DQ<10>";
142"M_G_DQ<8>";
143"M_G_DQ<27>";
144"M_G_DQS_DP<0>";
145"M_G_DQS_DP<1>";
146"M_G_DQS_DP<2>";
147"M_G_DQS_DP<3>";
148"M_G_DQS_DP<4>";
149"M_G_DQS_DP<6>";
150"M_G_DQS_DP<7>";
151"M_G_DQS_DP<8>";
152"M_G_DQS_DP<9>";
153"M_G_DQS_DN<0>";
154"M_G_DQS_DN<2>";
155"M_G_DQS_DN<3>";
156"M_G_DQS_DN<4>";
157"M_G_DQS_DN<6>";
158"M_G_DQS_DN<7>";
159"M_G_DQS_DN<8>";
160"M_G_DQS_DN<9>";
161"M_G_DQS_DP<10>";
162"M_G_DQS_DP<11>";
163"M_G_DQS_DP<12>";
164"M_G_DQS_DP<13>";
165"M_G_DQS_DP<14>";
166"M_G_DQS_DP<15>";
167"M_G_DQS_DP<16>";
168"M_G_DQS_DP<17>";
169"M_G_DQS_DN<10>";
170"M_G_DQS_DN<11>";
171"M_G_DQS_DN<12>";
172"M_G_DQS_DN<13>";
173"M_G_DQS_DN<14>";
174"M_G_DQS_DN<15>";
175"M_G_DQS_DN<16>";
176"M_G_DQS_DN<17>";
%"GND"
"1","(-2675,625)","0","mstr_symbols","I1";
;
VOLTAGE"0.0V"
SIZE"1B"
CDS_LIB"mstr_symbols"
BOM_COST"MEM"
BODY_TYPE"PLUMBING"
ROOM"DDR4_GH_G"
HDL_POWER"GND";
"A\NAC"13;
%"TAP"
"6","(125,2925)","2","mstr_standard","I100";
;
CDS_LIB"mstr_standard"
BODY_TYPE"PLUMBING"
HDL_TAP"TRUE";
"B \NAC \NWC"3;
"S \NAC"
BN"37"98;
%"TAP"
"6","(125,3125)","2","mstr_standard","I101";
;
CDS_LIB"mstr_standard"
BODY_TYPE"PLUMBING"
HDL_TAP"TRUE";
"B \NAC \NWC"3;
"S \NAC"
BN"41"95;
%"TAP"
"6","(125,3025)","2","mstr_standard","I102";
;
CDS_LIB"mstr_standard"
BODY_TYPE"PLUMBING"
HDL_TAP"TRUE";
"B \NAC \NWC"3;
"S \NAC"
BN"39"97;
%"TAP"
"6","(125,3075)","2","mstr_standard","I103";
;
CDS_LIB"mstr_standard"
BODY_TYPE"PLUMBING"
HDL_TAP"TRUE";
"B \NAC \NWC"3;
"S \NAC"
BN"40"96;
%"TAP"
"6","(125,3175)","2","mstr_standard","I104";
;
CDS_LIB"mstr_standard"
BODY_TYPE"PLUMBING"
HDL_TAP"TRUE";
"B \NAC \NWC"3;
"S \NAC"
BN"42"94;
%"TAP"
"6","(125,3225)","2","mstr_standard","I105";
;
CDS_LIB"mstr_standard"
BODY_TYPE"PLUMBING"
HDL_TAP"TRUE";
"B \NAC \NWC"3;
"S \NAC"
BN"43"93;
%"TAP"
"6","(125,3275)","2","mstr_standard","I106";
;
CDS_LIB"mstr_standard"
BODY_TYPE"PLUMBING"
HDL_TAP"TRUE";
"B \NAC \NWC"3;
"S \NAC"
BN"44"92;
%"TAP"
"6","(125,3325)","2","mstr_standard","I107";
;
CDS_LIB"mstr_standard"
BODY_TYPE"PLUMBING"
HDL_TAP"TRUE";
"B \NAC \NWC"3;
"S \NAC"
BN"45"91;
%"TAP"
"6","(125,3375)","2","mstr_standard","I108";
;
CDS_LIB"mstr_standard"
BODY_TYPE"PLUMBING"
HDL_TAP"TRUE";
"B \NAC \NWC"3;
"S \NAC"
BN"46"90;
%"TAP"
"6","(125,3475)","2","mstr_standard","I109";
;
CDS_LIB"mstr_standard"
BODY_TYPE"PLUMBING"
HDL_TAP"TRUE";
"B \NAC \NWC"3;
"S \NAC"
BN"48"135;
%"TAP"
"6","(125,3425)","2","mstr_standard","I110";
;
CDS_LIB"mstr_standard"
BODY_TYPE"PLUMBING"
HDL_TAP"TRUE";
"B \NAC \NWC"3;
"S \NAC"
BN"47"136;
%"TAP"
"6","(125,3525)","2","mstr_standard","I111";
;
CDS_LIB"mstr_standard"
BODY_TYPE"PLUMBING"
HDL_TAP"TRUE";
"B \NAC \NWC"3;
"S \NAC"
BN"49"134;
%"TAP"
"6","(125,3575)","2","mstr_standard","I112";
;
CDS_LIB"mstr_standard"
BODY_TYPE"PLUMBING"
HDL_TAP"TRUE";
"B \NAC \NWC"3;
"S \NAC"
BN"50"133;
%"TAP"
"6","(125,3625)","2","mstr_standard","I113";
;
CDS_LIB"mstr_standard"
BODY_TYPE"PLUMBING"
HDL_TAP"TRUE";
"B \NAC \NWC"3;
"S \NAC"
BN"51"132;
%"TAP"
"6","(125,3775)","2","mstr_standard","I114";
;
CDS_LIB"mstr_standard"
BODY_TYPE"PLUMBING"
HDL_TAP"TRUE";
"B \NAC \NWC"3;
"S \NAC"
BN"54"129;
%"TAP"
"6","(125,3725)","2","mstr_standard","I115";
;
CDS_LIB"mstr_standard"
BODY_TYPE"PLUMBING"
HDL_TAP"TRUE";
"B \NAC \NWC"3;
"S \NAC"
BN"53"130;
%"TAP"
"6","(125,3675)","2","mstr_standard","I116";
;
CDS_LIB"mstr_standard"
BODY_TYPE"PLUMBING"
HDL_TAP"TRUE";
"B \NAC \NWC"3;
"S \NAC"
BN"52"131;
%"TAP"
"6","(125,3825)","2","mstr_standard","I117";
;
CDS_LIB"mstr_standard"
BODY_TYPE"PLUMBING"
HDL_TAP"TRUE";
"B \NAC \NWC"3;
"S \NAC"
BN"55"89;
%"TAP"
"6","(125,3875)","2","mstr_standard","I118";
;
CDS_LIB"mstr_standard"
BODY_TYPE"PLUMBING"
HDL_TAP"TRUE";
"B \NAC \NWC"3;
"S \NAC"
BN"56"88;
%"PVPP_GHJ"
"1","(750,2750)","0","mstr_symbols","I119";
;
VOLTAGE"2.5V"
BOM_COST"MEM"
CDS_LIB"mstr_symbols"
BODY_TYPE"PLUMBING"
ROOM"DDR4_GH_G"
HDL_POWER"PVPP_GHJ";
"G\NAC"14;
%"TAP"
"6","(-1375,1825)","0","mstr_standard","I12";
;
CDS_LIB"mstr_standard"
BODY_TYPE"PLUMBING"
HDL_TAP"TRUE";
"B \NAC \NWC"12;
"S \NAC"
BN"0"42;
%"SCONN288_H44441003"
"2","(1750,4000)","0","mstr_sconn","I120";
;
CDS_SEC"2"
LOCATION"J9T1"
PART_NUMBER"H44441-003"
MATERIAL"SCONN"
BOM_SS"NOPOP"
PACK_TYPE"PIP"
BOM_COST"MEM"
CDS_LIB"mstr_sconn"
SEC_TYPE"PIP"
SEC"2"
CDS_LOCATION"J9T1"
ROOM"DDR4_GH_G";
"DQS0N"
$PN"152"153;
"DQS0P"
$PN"153"144;
"DQS10N"
$PN"19"169;
"DQS10P"
$PN"18"161;
"DQS11N"
$PN"30"170;
"DQS11P"
$PN"29"162;
"DQS12N"
$PN"41"171;
"DQS12P"
$PN"40"163;
"DQS13N"
$PN"100"172;
"DQS13P"
$PN"99"164;
"DQS14N"
$PN"111"173;
"DQS14P"
$PN"110"165;
"DQS15N"
$PN"122"174;
"DQS15P"
$PN"121"166;
"DQS16N"
$PN"133"175;
"DQS16P"
$PN"132"167;
"DQS17N"
$PN"52"176;
"DQS17P"
$PN"51"168;
"DQS1N"
$PN"163"23;
"DQS1P"
$PN"164"145;
"DQS2N"
$PN"174"154;
"DQS2P"
$PN"175"146;
"DQS3N"
$PN"185"155;
"DQS3P"
$PN"186"147;
"DQS4N"
$PN"244"156;
"DQS4P"
$PN"245"148;
"DQS5N"
$PN"255"26;
"DQS5P"
$PN"256"25;
"DQS6N"
$PN"266"157;
"DQS6P"
$PN"267"149;
"DQS7N"
$PN"277"158;
"DQS7P"
$PN"278"150;
"DQS8N"
$PN"196"159;
"DQS8P"
$PN"197"151;
"DQS9N"
$PN"8"160;
"DQS9P"
$PN"7"152;
%"TAP"
"6","(-1375,3925)","0","mstr_standard","I122";
;
CDS_LIB"mstr_standard"
BODY_TYPE"PLUMBING"
HDL_TAP"TRUE";
"B \NAC \NWC"4;
"S \NAC"
BN"11"77;
%"TAP"
"6","(-1375,3975)","0","mstr_standard","I123";
;
CDS_LIB"mstr_standard"
BODY_TYPE"PLUMBING"
HDL_TAP"TRUE";
"B \NAC \NWC"4;
"S \NAC"
BN"12"70;
%"TAP"
"6","(-1375,4125)","0","mstr_standard","I124";
;
CDS_LIB"mstr_standard"
BODY_TYPE"PLUMBING"
HDL_TAP"TRUE";
"B \NAC \NWC"4;
"S \NAC"
BN"15"80;
%"TAP"
"6","(-1375,4075)","0","mstr_standard","I125";
;
CDS_LIB"mstr_standard"
BODY_TYPE"PLUMBING"
HDL_TAP"TRUE";
"B \NAC \NWC"4;
"S \NAC"
BN"14"78;
%"TAP"
"6","(-1375,4025)","0","mstr_standard","I126";
;
CDS_LIB"mstr_standard"
BODY_TYPE"PLUMBING"
HDL_TAP"TRUE";
"B \NAC \NWC"4;
"S \NAC"
BN"13"71;
%"TAP"
"6","(-1375,4225)","0","mstr_standard","I127";
;
CDS_LIB"mstr_standard"
BODY_TYPE"PLUMBING"
HDL_TAP"TRUE";
"B \NAC \NWC"4;
"S \NAC"
BN"17"79;
%"TAP"
"6","(-1375,4175)","0","mstr_standard","I128";
;
CDS_LIB"mstr_standard"
BODY_TYPE"PLUMBING"
HDL_TAP"TRUE";
"B \NAC \NWC"4;
"S \NAC"
BN"16"81;
%"SCONN288_H44441003"
"1","(-625,2575)","0","mstr_sconn","I13";
;
CDS_SEC"1"
PART_NUMBER"H44441-003"
LOCATION"J9T1"
MATERIAL"SCONN"
BOM_SS"NOPOP"
PACK_TYPE"PIP"
BOM_COST"MEM"
CDS_LIB"mstr_sconn"
SEC_TYPE"PIP"
SEC"1"
CDS_LOCATION"J9T1"
ROOM"DDR4_GH_G";
"DQ<63>"
$PN"280"82;
"BA<1>"
$PN"224"61;
"CK1N"
$PN"219"52;
"CK0P"
$PN"74"53;
"S3_N_C<1>"
$PN"237"54;
"S2_N_C<0>"
$PN"93"56;
"S1_N"
$PN"89"57;
"DQ<29>"
$PN"181"83;
"DQ<28>"
$PN"36"84;
"C<2>"
$PN"235"60;
"A0"
$PN"79"62;
"A1"
$PN"72"63;
"A12"
$PN"65"70;
"A13"
$PN"232"71;
"A17"
$PN"234"79;
"A3"
$PN"71"64;
"A4"
$PN"214"65;
"A5"
$PN"213"72;
"A6"
$PN"69"73;
"A7"
$PN"211"22;
"A8"
$PN"68"74;
"A9"
$PN"66"75;
"CB<6>"
$PN"54"45;
"CB<5>"
$PN"192"46;
"CB<4>"
$PN"47"38;
"CB<3>"
$PN"201"39;
"CB<2>"
$PN"56"40;
"CB<1>"
$PN"194"41;
"CB<0>"
$PN"49"42;
"CK0N"
$PN"75"59;
"CKE<1>"
$PN"203"50;
"DQ<62>"
$PN"135"85;
"DQ<61>"
$PN"273"86;
"DQ<60>"
$PN"128"87;
"DQ<59>"
$PN"282"24;
"DQ<56>"
$PN"130"88;
"DQ<55>"
$PN"269"89;
"DQ<46>"
$PN"113"90;
"DQ<45>"
$PN"251"91;
"DQ<44>"
$PN"106"92;
"DQ<43>"
$PN"260"93;
"DQ<42>"
$PN"115"94;
"DQ<41>"
$PN"253"95;
"DQ<40>"
$PN"108"96;
"DQ<39>"
$PN"247"97;
"DQ<37>"
$PN"240"98;
"DQ<34>"
$PN"104"99;
"DQ<33>"
$PN"242"100;
"DQ<32>"
$PN"97"101;
"DQ<31>"
$PN"188"102;
"DQ<30>"
$PN"43"103;
"DQ<25>"
$PN"183"104;
"DQ<24>"
$PN"38"105;
"DQ<23>"
$PN"177"106;
"DQ<22>"
$PN"32"107;
"DQ<21>"
$PN"170"108;
"DQ<20>"
$PN"25"109;
"DQ<19>"
$PN"179"110;
"DQ<18>"
$PN"34"111;
"DQ<16>"
$PN"27"112;
"DQ<14>"
$PN"21"113;
"DQ<13>"
$PN"159"114;
"DQ<12>"
$PN"14"115;
"DQ<11>"
$PN"168"116;
"DQ<10>"
$PN"23"141;
"DQ<9>"
$PN"161"117;
"DQ<8>"
$PN"16"142;
"DQ<7>"
$PN"155"118;
"DQ<6>"
$PN"10"119;
"EVENT_N"
$PN"78"35;
"PAR"
$PN"222"43;
"RESET_N"
$PN"58"44;
"RFU<2>"
$PN"144"31;
"SCL"
$PN"141"37;
"SDA"
$PN"285"36;
"VREFCA"
$PN"146"28;
"CK1P"
$PN"218"55;
"BG<0>"
$PN"63"66;
"BG<1>"
$PN"207"67;
"BA<0>"
$PN"81"68;
"SA<0>"
$PN"139"19;
"VDDSPD"
$PN"284"19;
"SA<2>"
$PN"238"18;
"SA<1>"
$PN"140"18;
"DQ<1>"
$PN"150"120;
"DQ<0>"
$PN"5"121;
"ACT_N"
$PN"62"29;
"ALERT_N"
$PN"208"30;
"A2"
$PN"216"69;
"DQ<35>"
$PN"249"122;
"DQ<36>"
$PN"95"123;
"DQ<38>"
$PN"102"124;
"A10"
$PN"225"76;
"A11"
$PN"210"77;
"A14_WE_N"
$PN"228"78;
"A15_CAS_N"
$PN"86"80;
"A16_RAS_N"
$PN"82"81;
"CB<7>"
$PN"199"47;
"ODT<0>"
$PN"87"48;
"ODT<1>"
$PN"91"49;
"CKE<0>"
$PN"60"51;
"S0_N"
$PN"84"58;
"DQ<27>"
$PN"190"143;
"DQ<26>"
$PN"45"125;
"DQ<15>"
$PN"166"126;
"DQ<17>"
$PN"172"127;
"RFU<0>"
$PN"205"32;
"RFU<1>"
$PN"227"33;
"SAVE_N_NC"
$PN"230"34;
"DQ<57>"
$PN"275"27;
"DQ<58>"
$PN"137"128;
"DQ<54>"
$PN"124"129;
"DQ<53>"
$PN"262"130;
"DQ<52>"
$PN"117"131;
"DQ<51>"
$PN"271"132;
"DQ<50>"
$PN"126"133;
"DQ<49>"
$PN"264"134;
"DQ<48>"
$PN"119"135;
"DQ<47>"
$PN"258"136;
"DQ<2>"
$PN"12"137;
"DQ<3>"
$PN"157"138;
"DQ<4>"
$PN"3"139;
"DQ<5>"
$PN"148"140;
%"TAP"
"6","(125,3975)","2","mstr_standard","I135";
;
CDS_LIB"mstr_standard"
BODY_TYPE"PLUMBING"
HDL_TAP"TRUE";
"B \NAC \NWC"3;
"S \NAC"
BN"58"128;
%"TAP"
"6","(125,3925)","2","mstr_standard","I136";
;
CDS_LIB"mstr_standard"
BODY_TYPE"PLUMBING"
HDL_TAP"TRUE";
"B \NAC \NWC"3;
"S \NAC"
BN"57"27;
%"TAP"
"6","(125,4025)","2","mstr_standard","I137";
;
CDS_LIB"mstr_standard"
BODY_TYPE"PLUMBING"
HDL_TAP"TRUE";
"B \NAC \NWC"3;
"S \NAC"
BN"59"24;
%"TAP"
"6","(125,4125)","2","mstr_standard","I138";
;
CDS_LIB"mstr_standard"
BODY_TYPE"PLUMBING"
HDL_TAP"TRUE";
"B \NAC \NWC"3;
"S \NAC"
BN"61"86;
%"TAP"
"6","(125,4075)","2","mstr_standard","I139";
;
CDS_LIB"mstr_standard"
BODY_TYPE"PLUMBING"
HDL_TAP"TRUE";
"B \NAC \NWC"3;
"S \NAC"
BN"60"87;
%"TAP"
"6","(125,4175)","2","mstr_standard","I140";
;
CDS_LIB"mstr_standard"
BODY_TYPE"PLUMBING"
HDL_TAP"TRUE";
"B \NAC \NWC"3;
"S \NAC"
BN"62"85;
%"TAP"
"6","(125,4225)","2","mstr_standard","I141";
;
CDS_LIB"mstr_standard"
BODY_TYPE"PLUMBING"
HDL_TAP"TRUE";
"B \NAC \NWC"3;
"S \NAC"
BN"63"82;
%"GND"
"1","(2850,700)","2","mstr_symbols","I143";
;
VOLTAGE"0.0V"
SIZE"1B"
CDS_LIB"mstr_symbols"
BOM_COST"MEM"
BODY_TYPE"PLUMBING"
ROOM"DDR4_GH_G"
HDL_POWER"GND";
"A\NAC"15;
%"SCONN288_H44441003"
"3","(3550,2000)","0","mstr_sconn","I144";
;
CDS_SEC"3"
PART_NUMBER"H44441-003"
MATERIAL"SCONN"
LOCATION"J9T1"
BOM_SS"NOPOP"
PACK_TYPE"PIP"
BOM_COST"MEM"
CDS_LIB"mstr_sconn"
SEC_TYPE"PIP"
SEC"3"
CDS_LOCATION"J9T1"
ROOM"DDR4_GH_G";
"VSS<46>"
$PN"147"16;
"VSS<45>"
$PN"149"16;
"VSS<87>"
$PN"15"15;
"VSS<86>"
$PN"17"15;
"VSS<85>"
$PN"20"15;
"VSS<84>"
$PN"22"15;
"VSS<83>"
$PN"24"15;
"VSS<82>"
$PN"26"15;
"VSS<81>"
$PN"28"15;
"VSS<80>"
$PN"31"15;
"VSS<79>"
$PN"33"15;
"VSS<78>"
$PN"35"15;
"VSS<77>"
$PN"37"15;
"VSS<76>"
$PN"39"15;
"VSS<75>"
$PN"42"15;
"VSS<74>"
$PN"44"15;
"VSS<73>"
$PN"46"15;
"VSS<72>"
$PN"48"15;
"VSS<71>"
$PN"50"15;
"VSS<70>"
$PN"53"15;
"VSS<69>"
$PN"55"15;
"VSS<68>"
$PN"57"15;
"VSS<67>"
$PN"94"15;
"VSS<66>"
$PN"96"15;
"VSS<65>"
$PN"98"15;
"VSS<64>"
$PN"101"15;
"VSS<63>"
$PN"103"15;
"VSS<62>"
$PN"105"15;
"VSS<61>"
$PN"107"15;
"VSS<60>"
$PN"109"15;
"VSS<59>"
$PN"112"15;
"VSS<58>"
$PN"114"15;
"VSS<57>"
$PN"116"15;
"VSS<56>"
$PN"118"15;
"VSS<55>"
$PN"120"15;
"VSS<54>"
$PN"123"15;
"VSS<53>"
$PN"125"15;
"VSS<52>"
$PN"127"15;
"VSS<51>"
$PN"129"15;
"VSS<50>"
$PN"131"15;
"VSS<49>"
$PN"134"15;
"VSS<48>"
$PN"136"15;
"VSS<47>"
$PN"138"15;
"VSS<44>"
$PN"151"16;
"VSS<43>"
$PN"154"16;
"VSS<42>"
$PN"156"16;
"VSS<41>"
$PN"158"16;
"VSS<40>"
$PN"160"16;
"VSS<39>"
$PN"162"16;
"VSS<38>"
$PN"165"16;
"VSS<37>"
$PN"167"16;
"VSS<36>"
$PN"169"16;
"VSS<35>"
$PN"171"16;
"VSS<34>"
$PN"173"16;
"VSS<33>"
$PN"176"16;
"VSS<32>"
$PN"178"16;
"VSS<31>"
$PN"180"16;
"VSS<30>"
$PN"182"16;
"VSS<29>"
$PN"184"16;
"VSS<28>"
$PN"187"16;
"VSS<27>"
$PN"189"16;
"VSS<26>"
$PN"191"16;
"VSS<25>"
$PN"193"16;
"VSS<24>"
$PN"195"16;
"VSS<23>"
$PN"198"16;
"VSS<22>"
$PN"200"16;
"VSS<21>"
$PN"202"16;
"VSS<20>"
$PN"239"16;
"VSS<19>"
$PN"241"16;
"VSS<18>"
$PN"243"16;
"VSS<17>"
$PN"246"16;
"VSS<16>"
$PN"248"16;
"VSS<15>"
$PN"250"16;
"VSS<14>"
$PN"252"16;
"VSS<13>"
$PN"254"16;
"VSS<12>"
$PN"257"16;
"VSS<11>"
$PN"259"16;
"VSS<10>"
$PN"261"16;
"VSS<9>"
$PN"263"16;
"VSS<8>"
$PN"265"16;
"VSS<7>"
$PN"268"16;
"VSS<6>"
$PN"270"16;
"VSS<5>"
$PN"272"16;
"VSS<4>"
$PN"274"16;
"VSS<3>"
$PN"276"16;
"VSS<2>"
$PN"279"16;
"VSS<1>"
$PN"281"16;
"VSS<0>"
$PN"283"16;
"VSS<88>"
$PN"13"15;
"VSS<89>"
$PN"11"15;
"VSS<90>"
$PN"9"15;
"VSS<91>"
$PN"6"15;
"VSS<92>"
$PN"4"15;
"VSS<93>"
$PN"2"15;
%"TAP"
"6","(2450,3250)","2","mstr_standard","I148";
;
CDS_LIB"mstr_standard"
BODY_TYPE"PLUMBING"
HDL_TAP"TRUE";
"B \NAC \NWC"2;
"S \NAC"
BN"1"145;
%"TAP"
"6","(2450,3150)","2","mstr_standard","I149";
;
CDS_LIB"mstr_standard"
BODY_TYPE"PLUMBING"
HDL_TAP"TRUE";
"B \NAC \NWC"2;
"S \NAC"
BN"0"144;
%"TAP"
"6","(2450,3350)","2","mstr_standard","I150";
;
CDS_LIB"mstr_standard"
BODY_TYPE"PLUMBING"
HDL_TAP"TRUE";
"B \NAC \NWC"2;
"S \NAC"
BN"2"146;
%"TAP"
"6","(2650,3100)","2","mstr_standard","I151";
;
CDS_LIB"mstr_standard"
BODY_TYPE"PLUMBING"
HDL_TAP"TRUE";
"B \NAC \NWC"1;
"S \NAC"
BN"0"153;
%"TAP"
"6","(2650,3200)","2","mstr_standard","I152";
;
CDS_LIB"mstr_standard"
BODY_TYPE"PLUMBING"
HDL_TAP"TRUE";
"B \NAC \NWC"1;
"S \NAC"
BN"1"23;
%"TAP"
"6","(2650,3300)","2","mstr_standard","I153";
;
CDS_LIB"mstr_standard"
BODY_TYPE"PLUMBING"
HDL_TAP"TRUE";
"B \NAC \NWC"1;
"S \NAC"
BN"2"154;
%"TAP"
"6","(2450,3450)","2","mstr_standard","I154";
;
CDS_LIB"mstr_standard"
BODY_TYPE"PLUMBING"
HDL_TAP"TRUE";
"B \NAC \NWC"2;
"S \NAC"
BN"3"147;
%"TAP"
"6","(2450,3550)","2","mstr_standard","I155";
;
CDS_LIB"mstr_standard"
BODY_TYPE"PLUMBING"
HDL_TAP"TRUE";
"B \NAC \NWC"2;
"S \NAC"
BN"4"148;
%"TAP"
"6","(2450,3750)","2","mstr_standard","I156";
;
CDS_LIB"mstr_standard"
BODY_TYPE"PLUMBING"
HDL_TAP"TRUE";
"B \NAC \NWC"2;
"S \NAC"
BN"6"149;
%"TAP"
"6","(2450,3650)","2","mstr_standard","I157";
;
CDS_LIB"mstr_standard"
BODY_TYPE"PLUMBING"
HDL_TAP"TRUE";
"B \NAC \NWC"2;
"S \NAC"
BN"5"25;
%"TAP"
"6","(2450,3850)","2","mstr_standard","I158";
;
CDS_LIB"mstr_standard"
BODY_TYPE"PLUMBING"
HDL_TAP"TRUE";
"B \NAC \NWC"2;
"S \NAC"
BN"7"150;
%"TAP"
"6","(2650,3500)","2","mstr_standard","I159";
;
CDS_LIB"mstr_standard"
BODY_TYPE"PLUMBING"
HDL_TAP"TRUE";
"B \NAC \NWC"1;
"S \NAC"
BN"4"156;
%"TAP"
"6","(2650,3400)","2","mstr_standard","I160";
;
CDS_LIB"mstr_standard"
BODY_TYPE"PLUMBING"
HDL_TAP"TRUE";
"B \NAC \NWC"1;
"S \NAC"
BN"3"155;
%"TAP"
"6","(2650,3600)","2","mstr_standard","I161";
;
CDS_LIB"mstr_standard"
BODY_TYPE"PLUMBING"
HDL_TAP"TRUE";
"B \NAC \NWC"1;
"S \NAC"
BN"5"26;
%"TAP"
"6","(2650,3800)","2","mstr_standard","I162";
;
CDS_LIB"mstr_standard"
BODY_TYPE"PLUMBING"
HDL_TAP"TRUE";
"B \NAC \NWC"1;
"S \NAC"
BN"7"158;
%"TAP"
"6","(2650,3700)","2","mstr_standard","I163";
;
CDS_LIB"mstr_standard"
BODY_TYPE"PLUMBING"
HDL_TAP"TRUE";
"B \NAC \NWC"1;
"S \NAC"
BN"6"157;
%"GND"
"1","(4250,700)","2","mstr_symbols","I164";
;
VOLTAGE"0.0V"
SIZE"1B"
CDS_LIB"mstr_symbols"
BOM_COST"MEM"
BODY_TYPE"PLUMBING"
ROOM"DDR4_GH_G"
HDL_POWER"GND";
"A\NAC"16;
%"TAP"
"6","(2450,3950)","2","mstr_standard","I165";
;
CDS_LIB"mstr_standard"
BODY_TYPE"PLUMBING"
HDL_TAP"TRUE";
"B \NAC \NWC"2;
"S \NAC"
BN"8"151;
%"TAP"
"6","(2450,4150)","2","mstr_standard","I166";
;
CDS_LIB"mstr_standard"
BODY_TYPE"PLUMBING"
HDL_TAP"TRUE";
"B \NAC \NWC"2;
"S \NAC"
BN"10"161;
%"TAP"
"6","(2450,4050)","2","mstr_standard","I167";
;
CDS_LIB"mstr_standard"
BODY_TYPE"PLUMBING"
HDL_TAP"TRUE";
"B \NAC \NWC"2;
"S \NAC"
BN"9"152;
%"TAP"
"6","(2450,4250)","2","mstr_standard","I168";
;
CDS_LIB"mstr_standard"
BODY_TYPE"PLUMBING"
HDL_TAP"TRUE";
"B \NAC \NWC"2;
"S \NAC"
BN"11"162;
%"TAP"
"6","(2450,4350)","2","mstr_standard","I169";
;
CDS_LIB"mstr_standard"
BODY_TYPE"PLUMBING"
HDL_TAP"TRUE";
"B \NAC \NWC"2;
"S \NAC"
BN"12"163;
%"TAP"
"6","(2650,4000)","2","mstr_standard","I170";
;
CDS_LIB"mstr_standard"
BODY_TYPE"PLUMBING"
HDL_TAP"TRUE";
"B \NAC \NWC"1;
"S \NAC"
BN"9"160;
%"TAP"
"6","(2650,4100)","2","mstr_standard","I171";
;
CDS_LIB"mstr_standard"
BODY_TYPE"PLUMBING"
HDL_TAP"TRUE";
"B \NAC \NWC"1;
"S \NAC"
BN"10"169;
%"TAP"
"6","(2650,3900)","2","mstr_standard","I172";
;
CDS_LIB"mstr_standard"
BODY_TYPE"PLUMBING"
HDL_TAP"TRUE";
"B \NAC \NWC"1;
"S \NAC"
BN"8"159;
%"TAP"
"6","(2650,4200)","2","mstr_standard","I173";
;
CDS_LIB"mstr_standard"
BODY_TYPE"PLUMBING"
HDL_TAP"TRUE";
"B \NAC \NWC"1;
"S \NAC"
BN"11"170;
%"TAP"
"6","(2650,4400)","2","mstr_standard","I174";
;
CDS_LIB"mstr_standard"
BODY_TYPE"PLUMBING"
HDL_TAP"TRUE";
"B \NAC \NWC"1;
"S \NAC"
BN"13"172;
%"TAP"
"6","(2650,4300)","2","mstr_standard","I175";
;
CDS_LIB"mstr_standard"
BODY_TYPE"PLUMBING"
HDL_TAP"TRUE";
"B \NAC \NWC"1;
"S \NAC"
BN"12"171;
%"TAP"
"6","(2450,4450)","2","mstr_standard","I176";
;
CDS_LIB"mstr_standard"
BODY_TYPE"PLUMBING"
HDL_TAP"TRUE";
"B \NAC \NWC"2;
"S \NAC"
BN"13"164;
%"TAP"
"6","(2450,4550)","2","mstr_standard","I177";
;
CDS_LIB"mstr_standard"
BODY_TYPE"PLUMBING"
HDL_TAP"TRUE";
"B \NAC \NWC"2;
"S \NAC"
BN"14"165;
%"TAP"
"6","(2450,4650)","2","mstr_standard","I178";
;
CDS_LIB"mstr_standard"
BODY_TYPE"PLUMBING"
HDL_TAP"TRUE";
"B \NAC \NWC"2;
"S \NAC"
BN"15"166;
%"TAP"
"6","(2450,4750)","2","mstr_standard","I179";
;
CDS_LIB"mstr_standard"
BODY_TYPE"PLUMBING"
HDL_TAP"TRUE";
"B \NAC \NWC"2;
"S \NAC"
BN"16"167;
%"TAP"
"6","(2450,4850)","2","mstr_standard","I180";
;
CDS_LIB"mstr_standard"
BODY_TYPE"PLUMBING"
HDL_TAP"TRUE";
"B \NAC \NWC"2;
"S \NAC"
BN"17"168;
%"TAP"
"6","(2650,4600)","2","mstr_standard","I181";
;
CDS_LIB"mstr_standard"
BODY_TYPE"PLUMBING"
HDL_TAP"TRUE";
"B \NAC \NWC"1;
"S \NAC"
BN"15"174;
%"TAP"
"6","(2650,4500)","2","mstr_standard","I182";
;
CDS_LIB"mstr_standard"
BODY_TYPE"PLUMBING"
HDL_TAP"TRUE";
"B \NAC \NWC"1;
"S \NAC"
BN"14"173;
%"TAP"
"6","(2650,4800)","2","mstr_standard","I183";
;
CDS_LIB"mstr_standard"
BODY_TYPE"PLUMBING"
HDL_TAP"TRUE";
"B \NAC \NWC"1;
"S \NAC"
BN"17"176;
%"TAP"
"6","(2650,4700)","2","mstr_standard","I184";
;
CDS_LIB"mstr_standard"
BODY_TYPE"PLUMBING"
HDL_TAP"TRUE";
"B \NAC \NWC"1;
"S \NAC"
BN"16"175;
%"P12V_NVDIMM_GHJ"
"1","(2150,2725)","0","mstr_symbols","I187";
;
VOLTAGE"12.0"
CDS_LIB"mstr_symbols"
BODY_TYPE"PLUMBING"
HDL_POWER"P12V_NVDIMM_GHJ";
"G\NAC"17;
%"CAP_A"
"1","(-2675,875)","2","dev_discrete","I2";
;
LOCATION"C9T7"
PART_NUMBER"A36096-045"
VALUE"0.01UF"
TOLERANCE"10%"
PACK_TYPE"0402V"
VOLTAGE"25V"
MATERIAL"X7R"
CDS_LOCATION"C9T7"
BOM_COST"MEM"
CDS_LIB"dev_discrete"
CDS_SEC"1"
$SEC"1"
ROOM"DDR4_GH_G";
"B"
$PN"2"13;
"A"
$PN"1"28;
%"TAP"
"6","(-1375,1875)","0","mstr_standard","I21";
;
CDS_LIB"mstr_standard"
BODY_TYPE"PLUMBING"
HDL_TAP"TRUE";
"B \NAC \NWC"12;
"S \NAC"
BN"1"41;
%"TAP"
"6","(-1375,1925)","0","mstr_standard","I22";
;
CDS_LIB"mstr_standard"
BODY_TYPE"PLUMBING"
HDL_TAP"TRUE";
"B \NAC \NWC"12;
"S \NAC"
BN"2"40;
%"TAP"
"6","(-1375,1975)","0","mstr_standard","I23";
;
CDS_LIB"mstr_standard"
BODY_TYPE"PLUMBING"
HDL_TAP"TRUE";
"B \NAC \NWC"12;
"S \NAC"
BN"3"39;
%"TAP"
"6","(-1375,2075)","0","mstr_standard","I24";
;
CDS_LIB"mstr_standard"
BODY_TYPE"PLUMBING"
HDL_TAP"TRUE";
"B \NAC \NWC"12;
"S \NAC"
BN"5"46;
%"TAP"
"6","(-1375,2025)","0","mstr_standard","I25";
;
CDS_LIB"mstr_standard"
BODY_TYPE"PLUMBING"
HDL_TAP"TRUE";
"B \NAC \NWC"12;
"S \NAC"
BN"4"38;
%"TAP"
"6","(-1375,2175)","0","mstr_standard","I26";
;
CDS_LIB"mstr_standard"
BODY_TYPE"PLUMBING"
HDL_TAP"TRUE";
"B \NAC \NWC"12;
"S \NAC"
BN"7"47;
%"TAP"
"6","(-1375,2125)","0","mstr_standard","I27";
;
CDS_LIB"mstr_standard"
BODY_TYPE"PLUMBING"
HDL_TAP"TRUE";
"B \NAC \NWC"12;
"S \NAC"
BN"6"45;
%"TAP"
"6","(-1375,2325)","0","mstr_standard","I28";
;
CDS_LIB"mstr_standard"
BODY_TYPE"PLUMBING"
HDL_TAP"TRUE";
"B \NAC \NWC"11;
"S \NAC"
BN"3"49;
%"TAP"
"6","(-1375,2275)","0","mstr_standard","I29";
;
CDS_LIB"mstr_standard"
BODY_TYPE"PLUMBING"
HDL_TAP"TRUE";
"B \NAC \NWC"11;
"S \NAC"
BN"2"48;
%"GND"
"1","(-3325,1225)","2","mstr_symbols","I3";
;
VOLTAGE"0.0V"
SIZE"1B"
CDS_LIB"mstr_symbols"
BOM_COST"MEM"
BODY_TYPE"PLUMBING"
ROOM"DDR4_GH_G"
HDL_POWER"GND";
"A\NAC"18;
%"TAP"
"6","(-1375,2425)","0","mstr_standard","I30";
;
CDS_LIB"mstr_standard"
BODY_TYPE"PLUMBING"
HDL_TAP"TRUE";
"B \NAC \NWC"10;
"S \NAC"
BN"2"51;
%"TAP"
"6","(-1375,2475)","0","mstr_standard","I31";
;
CDS_LIB"mstr_standard"
BODY_TYPE"PLUMBING"
HDL_TAP"TRUE";
"B \NAC \NWC"10;
"S \NAC"
BN"3"50;
%"TAP"
"6","(-1375,2575)","0","mstr_standard","I32";
;
CDS_LIB"mstr_standard"
BODY_TYPE"PLUMBING"
HDL_TAP"TRUE";
"B \NAC \NWC"8;
"S \NAC"
BN"4"58;
%"TAP"
"6","(-1375,2675)","0","mstr_standard","I33";
;
CDS_LIB"mstr_standard"
BODY_TYPE"PLUMBING"
HDL_TAP"TRUE";
"B \NAC \NWC"8;
"S \NAC"
BN"6"56;
%"TAP"
"6","(-1375,2625)","0","mstr_standard","I34";
;
CDS_LIB"mstr_standard"
BODY_TYPE"PLUMBING"
HDL_TAP"TRUE";
"B \NAC \NWC"8;
"S \NAC"
BN"5"57;
%"TAP"
"6","(-1375,2725)","0","mstr_standard","I35";
;
CDS_LIB"mstr_standard"
BODY_TYPE"PLUMBING"
HDL_TAP"TRUE";
"B \NAC \NWC"8;
"S \NAC"
BN"7"54;
%"TAP"
"6","(-1575,2975)","0","mstr_standard","I40";
;
CDS_LIB"mstr_standard"
BODY_TYPE"PLUMBING"
HDL_TAP"TRUE";
"B \NAC \NWC"7;
"S \NAC"
BN"3"52;
%"TAP"
"6","(-1575,2875)","0","mstr_standard","I41";
;
CDS_LIB"mstr_standard"
BODY_TYPE"PLUMBING"
HDL_TAP"TRUE";
"B \NAC \NWC"7;
"S \NAC"
BN"2"59;
%"TAP"
"6","(-1375,2925)","0","mstr_standard","I42";
;
CDS_LIB"mstr_standard"
BODY_TYPE"PLUMBING"
HDL_TAP"TRUE";
"B \NAC \NWC"9;
"S \NAC"
BN"2"53;
%"TAP"
"6","(-1375,3025)","0","mstr_standard","I43";
;
CDS_LIB"mstr_standard"
BODY_TYPE"PLUMBING"
HDL_TAP"TRUE";
"B \NAC \NWC"9;
"S \NAC"
BN"3"55;
%"TAP"
"6","(-1375,3125)","0","mstr_standard","I44";
;
CDS_LIB"mstr_standard"
BODY_TYPE"PLUMBING"
HDL_TAP"TRUE";
"B \NAC \NWC"6;
"S \NAC"
BN"0"66;
%"TAP"
"6","(-1375,3225)","0","mstr_standard","I45";
;
CDS_LIB"mstr_standard"
BODY_TYPE"PLUMBING"
HDL_TAP"TRUE";
"B \NAC \NWC"5;
"S \NAC"
BN"0"68;
%"TAP"
"6","(-1375,3175)","0","mstr_standard","I46";
;
CDS_LIB"mstr_standard"
BODY_TYPE"PLUMBING"
HDL_TAP"TRUE";
"B \NAC \NWC"6;
"S \NAC"
BN"1"67;
%"TAP"
"6","(-1375,3275)","0","mstr_standard","I47";
;
CDS_LIB"mstr_standard"
BODY_TYPE"PLUMBING"
HDL_TAP"TRUE";
"B \NAC \NWC"5;
"S \NAC"
BN"1"61;
%"TAP"
"6","(-1375,3375)","0","mstr_standard","I48";
;
CDS_LIB"mstr_standard"
BODY_TYPE"PLUMBING"
HDL_TAP"TRUE";
"B \NAC \NWC"4;
"S \NAC"
BN"0"62;
%"TAP"
"6","(-1375,3475)","0","mstr_standard","I49";
;
CDS_LIB"mstr_standard"
BODY_TYPE"PLUMBING"
HDL_TAP"TRUE";
"B \NAC \NWC"4;
"S \NAC"
BN"2"69;
%"PVPP_GHJ"
"1","(-3325,1575)","0","mstr_symbols","I5";
;
VOLTAGE"2.5V"
BOM_COST"MEM"
CDS_LIB"mstr_symbols"
BODY_TYPE"PLUMBING"
ROOM"DDR4_GH_G"
HDL_POWER"PVPP_GHJ";
"G\NAC"19;
%"TAP"
"6","(-1375,3425)","0","mstr_standard","I50";
;
CDS_LIB"mstr_standard"
BODY_TYPE"PLUMBING"
HDL_TAP"TRUE";
"B \NAC \NWC"4;
"S \NAC"
BN"1"63;
%"TAP"
"6","(-1375,3575)","0","mstr_standard","I51";
;
CDS_LIB"mstr_standard"
BODY_TYPE"PLUMBING"
HDL_TAP"TRUE";
"B \NAC \NWC"4;
"S \NAC"
BN"4"65;
%"TAP"
"6","(-1375,3525)","0","mstr_standard","I52";
;
CDS_LIB"mstr_standard"
BODY_TYPE"PLUMBING"
HDL_TAP"TRUE";
"B \NAC \NWC"4;
"S \NAC"
BN"3"64;
%"TAP"
"6","(-1375,3625)","0","mstr_standard","I53";
;
CDS_LIB"mstr_standard"
BODY_TYPE"PLUMBING"
HDL_TAP"TRUE";
"B \NAC \NWC"4;
"S \NAC"
BN"5"72;
%"TAP"
"6","(-1375,3675)","0","mstr_standard","I54";
;
CDS_LIB"mstr_standard"
BODY_TYPE"PLUMBING"
HDL_TAP"TRUE";
"B \NAC \NWC"4;
"S \NAC"
BN"6"73;
%"TAP"
"6","(-1375,3725)","0","mstr_standard","I55";
;
CDS_LIB"mstr_standard"
BODY_TYPE"PLUMBING"
HDL_TAP"TRUE";
"B \NAC \NWC"4;
"S \NAC"
BN"7"22;
%"TAP"
"6","(-1375,3825)","0","mstr_standard","I56";
;
CDS_LIB"mstr_standard"
BODY_TYPE"PLUMBING"
HDL_TAP"TRUE";
"B \NAC \NWC"4;
"S \NAC"
BN"9"75;
%"TAP"
"6","(-1375,3775)","0","mstr_standard","I57";
;
CDS_LIB"mstr_standard"
BODY_TYPE"PLUMBING"
HDL_TAP"TRUE";
"B \NAC \NWC"4;
"S \NAC"
BN"8"74;
%"TAP"
"6","(-1375,3875)","0","mstr_standard","I58";
;
CDS_LIB"mstr_standard"
BODY_TYPE"PLUMBING"
HDL_TAP"TRUE";
"B \NAC \NWC"4;
"S \NAC"
BN"10"76;
%"TAP"
"6","(125,1075)","2","mstr_standard","I59";
;
CDS_LIB"mstr_standard"
BODY_TYPE"PLUMBING"
HDL_TAP"TRUE";
"B \NAC \NWC"3;
"S \NAC"
BN"0"121;
%"TAP"
"6","(125,1125)","2","mstr_standard","I60";
;
CDS_LIB"mstr_standard"
BODY_TYPE"PLUMBING"
HDL_TAP"TRUE";
"B \NAC \NWC"3;
"S \NAC"
BN"1"120;
%"TAP"
"6","(125,1175)","2","mstr_standard","I61";
;
CDS_LIB"mstr_standard"
BODY_TYPE"PLUMBING"
HDL_TAP"TRUE";
"B \NAC \NWC"3;
"S \NAC"
BN"2"137;
%"TAP"
"6","(125,1325)","2","mstr_standard","I62";
;
CDS_LIB"mstr_standard"
BODY_TYPE"PLUMBING"
HDL_TAP"TRUE";
"B \NAC \NWC"3;
"S \NAC"
BN"5"140;
%"TAP"
"6","(125,1275)","2","mstr_standard","I63";
;
CDS_LIB"mstr_standard"
BODY_TYPE"PLUMBING"
HDL_TAP"TRUE";
"B \NAC \NWC"3;
"S \NAC"
BN"4"139;
%"TAP"
"6","(125,1225)","2","mstr_standard","I64";
;
CDS_LIB"mstr_standard"
BODY_TYPE"PLUMBING"
HDL_TAP"TRUE";
"B \NAC \NWC"3;
"S \NAC"
BN"3"138;
%"TAP"
"6","(125,1375)","2","mstr_standard","I65";
;
CDS_LIB"mstr_standard"
BODY_TYPE"PLUMBING"
HDL_TAP"TRUE";
"B \NAC \NWC"3;
"S \NAC"
BN"6"119;
%"TAP"
"6","(125,1425)","2","mstr_standard","I66";
;
CDS_LIB"mstr_standard"
BODY_TYPE"PLUMBING"
HDL_TAP"TRUE";
"B \NAC \NWC"3;
"S \NAC"
BN"7"118;
%"TAP"
"6","(125,1475)","2","mstr_standard","I67";
;
CDS_LIB"mstr_standard"
BODY_TYPE"PLUMBING"
HDL_TAP"TRUE";
"B \NAC \NWC"3;
"S \NAC"
BN"8"142;
%"TAP"
"6","(125,1525)","2","mstr_standard","I68";
;
CDS_LIB"mstr_standard"
BODY_TYPE"PLUMBING"
HDL_TAP"TRUE";
"B \NAC \NWC"3;
"S \NAC"
BN"9"117;
%"TAP"
"6","(125,1575)","2","mstr_standard","I69";
;
CDS_LIB"mstr_standard"
BODY_TYPE"PLUMBING"
HDL_TAP"TRUE";
"B \NAC \NWC"3;
"S \NAC"
BN"10"141;
%"TAP"
"6","(125,1725)","2","mstr_standard","I70";
;
CDS_LIB"mstr_standard"
BODY_TYPE"PLUMBING"
HDL_TAP"TRUE";
"B \NAC \NWC"3;
"S \NAC"
BN"13"114;
%"TAP"
"6","(125,1625)","2","mstr_standard","I71";
;
CDS_LIB"mstr_standard"
BODY_TYPE"PLUMBING"
HDL_TAP"TRUE";
"B \NAC \NWC"3;
"S \NAC"
BN"11"116;
%"TAP"
"6","(125,1675)","2","mstr_standard","I72";
;
CDS_LIB"mstr_standard"
BODY_TYPE"PLUMBING"
HDL_TAP"TRUE";
"B \NAC \NWC"3;
"S \NAC"
BN"12"115;
%"TAP"
"6","(125,1775)","2","mstr_standard","I73";
;
CDS_LIB"mstr_standard"
BODY_TYPE"PLUMBING"
HDL_TAP"TRUE";
"B \NAC \NWC"3;
"S \NAC"
BN"14"113;
%"TAP"
"6","(125,1825)","2","mstr_standard","I74";
;
CDS_LIB"mstr_standard"
BODY_TYPE"PLUMBING"
HDL_TAP"TRUE";
"B \NAC \NWC"3;
"S \NAC"
BN"15"126;
%"SCONN288_H44441003"
"4","(1450,1750)","0","mstr_sconn","I75";
;
CDS_SEC"4"
LOCATION"J9T1"
PART_NUMBER"H44441-003"
MATERIAL"SCONN"
BOM_SS"NOPOP"
PACK_TYPE"PIP"
BOM_COST"MEM"
CDS_LIB"mstr_sconn"
SEC_TYPE"PIP"
SEC"4"
CDS_LOCATION"J9T1"
ROOM"DDR4_GH_G";
"VDD<0>"
$PN"236"20;
"VDD<6>"
$PN"220"20;
"VDD<10>"
$PN"209"20;
"VDD<13>"
$PN"92"20;
"VDD<16>"
$PN"85"20;
"VDD<19>"
$PN"76"20;
"VDD<23>"
$PN"64"20;
"VDD<25>"
$PN"59"20;
"VTT<0>"
$PN"221"21;
"12V<1>"
$PN"1"17;
"12V<0>"
$PN"145"17;
"VDD<24>"
$PN"61"20;
"VDD<22>"
$PN"67"20;
"VDD<21>"
$PN"70"20;
"VDD<20>"
$PN"73"20;
"VDD<18>"
$PN"80"20;
"VDD<17>"
$PN"83"20;
"VDD<15>"
$PN"88"20;
"VDD<14>"
$PN"90"20;
"VDD<12>"
$PN"204"20;
"VDD<11>"
$PN"206"20;
"VDD<9>"
$PN"212"20;
"VDD<8>"
$PN"215"20;
"VDD<7>"
$PN"217"20;
"VDD<5>"
$PN"223"20;
"VDD<4>"
$PN"226"20;
"VDD<3>"
$PN"229"20;
"VDD<2>"
$PN"231"20;
"VDD<1>"
$PN"233"20;
"VPP<4>"
$PN"142"14;
"VPP<3>"
$PN"143"14;
"VPP<2>"
$PN"288"14;
"VPP<1>"
$PN"286"14;
"VPP<0>"
$PN"287"14;
"VTT<1>"
$PN"77"21;
%"TAP"
"6","(125,1925)","2","mstr_standard","I76";
;
CDS_LIB"mstr_standard"
BODY_TYPE"PLUMBING"
HDL_TAP"TRUE";
"B \NAC \NWC"3;
"S \NAC"
BN"17"127;
%"TAP"
"6","(125,1875)","2","mstr_standard","I77";
;
CDS_LIB"mstr_standard"
BODY_TYPE"PLUMBING"
HDL_TAP"TRUE";
"B \NAC \NWC"3;
"S \NAC"
BN"16"112;
%"TAP"
"6","(125,1975)","2","mstr_standard","I78";
;
CDS_LIB"mstr_standard"
BODY_TYPE"PLUMBING"
HDL_TAP"TRUE";
"B \NAC \NWC"3;
"S \NAC"
BN"18"111;
%"TAP"
"6","(125,2025)","2","mstr_standard","I79";
;
CDS_LIB"mstr_standard"
BODY_TYPE"PLUMBING"
HDL_TAP"TRUE";
"B \NAC \NWC"3;
"S \NAC"
BN"19"110;
%"TAP"
"6","(125,2075)","2","mstr_standard","I80";
;
CDS_LIB"mstr_standard"
BODY_TYPE"PLUMBING"
HDL_TAP"TRUE";
"B \NAC \NWC"3;
"S \NAC"
BN"20"109;
%"TAP"
"6","(125,2225)","2","mstr_standard","I81";
;
CDS_LIB"mstr_standard"
BODY_TYPE"PLUMBING"
HDL_TAP"TRUE";
"B \NAC \NWC"3;
"S \NAC"
BN"23"106;
%"TAP"
"6","(125,2175)","2","mstr_standard","I82";
;
CDS_LIB"mstr_standard"
BODY_TYPE"PLUMBING"
HDL_TAP"TRUE";
"B \NAC \NWC"3;
"S \NAC"
BN"22"107;
%"TAP"
"6","(125,2125)","2","mstr_standard","I83";
;
CDS_LIB"mstr_standard"
BODY_TYPE"PLUMBING"
HDL_TAP"TRUE";
"B \NAC \NWC"3;
"S \NAC"
BN"21"108;
%"TAP"
"6","(125,2325)","2","mstr_standard","I84";
;
CDS_LIB"mstr_standard"
BODY_TYPE"PLUMBING"
HDL_TAP"TRUE";
"B \NAC \NWC"3;
"S \NAC"
BN"25"104;
%"TAP"
"6","(125,2275)","2","mstr_standard","I85";
;
CDS_LIB"mstr_standard"
BODY_TYPE"PLUMBING"
HDL_TAP"TRUE";
"B \NAC \NWC"3;
"S \NAC"
BN"24"105;
%"TAP"
"6","(125,2475)","2","mstr_standard","I86";
;
CDS_LIB"mstr_standard"
BODY_TYPE"PLUMBING"
HDL_TAP"TRUE";
"B \NAC \NWC"3;
"S \NAC"
BN"28"84;
%"TAP"
"6","(125,2425)","2","mstr_standard","I87";
;
CDS_LIB"mstr_standard"
BODY_TYPE"PLUMBING"
HDL_TAP"TRUE";
"B \NAC \NWC"3;
"S \NAC"
BN"27"143;
%"TAP"
"6","(125,2375)","2","mstr_standard","I88";
;
CDS_LIB"mstr_standard"
BODY_TYPE"PLUMBING"
HDL_TAP"TRUE";
"B \NAC \NWC"3;
"S \NAC"
BN"26"125;
%"TAP"
"6","(125,2525)","2","mstr_standard","I89";
;
CDS_LIB"mstr_standard"
BODY_TYPE"PLUMBING"
HDL_TAP"TRUE";
"B \NAC \NWC"3;
"S \NAC"
BN"29"83;
%"TAP"
"6","(125,2575)","2","mstr_standard","I90";
;
CDS_LIB"mstr_standard"
BODY_TYPE"PLUMBING"
HDL_TAP"TRUE";
"B \NAC \NWC"3;
"S \NAC"
BN"30"103;
%"TAP"
"6","(125,2675)","2","mstr_standard","I91";
;
CDS_LIB"mstr_standard"
BODY_TYPE"PLUMBING"
HDL_TAP"TRUE";
"B \NAC \NWC"3;
"S \NAC"
BN"32"101;
%"TAP"
"6","(125,2725)","2","mstr_standard","I92";
;
CDS_LIB"mstr_standard"
BODY_TYPE"PLUMBING"
HDL_TAP"TRUE";
"B \NAC \NWC"3;
"S \NAC"
BN"33"100;
%"TAP"
"6","(125,2625)","2","mstr_standard","I93";
;
CDS_LIB"mstr_standard"
BODY_TYPE"PLUMBING"
HDL_TAP"TRUE";
"B \NAC \NWC"3;
"S \NAC"
BN"31"102;
%"TAP"
"6","(125,2825)","2","mstr_standard","I94";
;
CDS_LIB"mstr_standard"
BODY_TYPE"PLUMBING"
HDL_TAP"TRUE";
"B \NAC \NWC"3;
"S \NAC"
BN"35"122;
%"TAP"
"6","(125,2775)","2","mstr_standard","I95";
;
CDS_LIB"mstr_standard"
BODY_TYPE"PLUMBING"
HDL_TAP"TRUE";
"B \NAC \NWC"3;
"S \NAC"
BN"34"99;
%"PVDDQ_GHJ"
"1","(400,2300)","0","mstr_symbols","I96";
;
VOLTAGE"1.2V"
BOM_COST"MEM"
CDS_LIB"mstr_symbols"
BODY_TYPE"PLUMBING"
ROOM"DDR4_GH_G"
HDL_POWER"PVDDQ_GHJ";
"G\NAC"20;
%"PVTT_GHJ"
"1","(600,2450)","0","mstr_symbols","I97";
;
VOLTAGE"0.6V"
BOM_COST"MEM"
CDS_LIB"mstr_symbols"
BODY_TYPE"PLUMBING"
ROOM"DDR4_GH_G"
HDL_POWER"PVTT_GHJ";
"G\NAC"21;
%"TAP"
"6","(125,2875)","2","mstr_standard","I98";
;
CDS_LIB"mstr_standard"
BODY_TYPE"PLUMBING"
HDL_TAP"TRUE";
"B \NAC \NWC"3;
"S \NAC"
BN"36"123;
%"TAP"
"6","(125,2975)","2","mstr_standard","I99";
;
CDS_LIB"mstr_standard"
BODY_TYPE"PLUMBING"
HDL_TAP"TRUE";
"B \NAC \NWC"3;
"S \NAC"
BN"38"124;
END.
